(kicad_pcb
	(version 20260206)
	(generator "pcbnew")
	(generator_version "10.0")
	(general
		(thickness 1.6)
		(legacy_teardrops no)
	)
	(paper "A4")
	(title_block
		(title "9052_F0T_PDB_Converter_Brick_F_V03_1208_1600_OCP.brd")
		(comment 1 "Grand Teton / footprints 35-40 of 578")
	)
	(layers
		(0 "F.Cu" signal "TOP")
		(4 "In1.Cu" signal "GND")
		(6 "In2.Cu" signal "IN1")
		(8 "In3.Cu" signal "GND1")
		(10 "In4.Cu" signal "VCC")
		(12 "In5.Cu" signal "VCC1")
		(14 "In6.Cu" signal "GND2")
		(16 "In7.Cu" signal "IN2")
		(18 "In8.Cu" signal "GND3")
		(2 "B.Cu" signal "BOTTOM")
		(9 "F.Adhes" user "F.Adhesive")
		(11 "B.Adhes" user "B.Adhesive")
		(13 "F.Paste" user "Package Geometry/Pastemask Top")
		(15 "B.Paste" user "Package Geometry/Pastemask Bottom")
		(5 "F.SilkS" user "Ref Des/Silkscreen Top")
		(7 "B.SilkS" user "Ref Des/Silkscreen Bottom")
		(1 "F.Mask" user "Board Geometry/Soldermask Top")
		(3 "B.Mask" user "Board Geometry/Soldermask Bottom")
		(17 "Dwgs.User" user "User.Drawings")
		(19 "Cmts.User" user "User.Comments")
		(21 "Eco1.User" user "User.Eco1")
		(23 "Eco2.User" user "User.Eco2")
		(25 "Edge.Cuts" user "Board Geometry/Outline")
		(27 "Margin" user)
		(31 "F.CrtYd" user "Package Geometry/Place Bound Top")
		(29 "B.CrtYd" user "Package Geometry/Place Bound Bottom")
		(35 "F.Fab" user "Ref Des/Assembly Top")
		(33 "B.Fab" user "Ref Des/Assembly Bottom")
	)
	(footprint ""
		(layer "F.Cu")
		(at 37.338 -60.5282 -90)
		(property "Reference" "R5895"
			(at 0 0 270)
			(layer "F.SilkS")
			(hide yes)
			(effects
				(font
					(size 1.27 1.27)
				)
			)
		)
		(property "Value" ""
			(at 0 0 270)
			(layer "F.Fab")
			(effects
				(font
					(size 1.27 1.27)
				)
			)
		)
		(duplicate_pad_numbers_are_jumpers no)
		(fp_line
			(start -1.2954 0.5842)
			(end -1.2954 -0.5842)
			(stroke
				(width 0.1524)
				(type default)
			)
			(layer "F.SilkS")
		)
		(fp_line
			(start 1.2954 0.5842)
			(end -1.2954 0.5842)
			(stroke
				(width 0.1524)
				(type default)
			)
			(layer "F.SilkS")
		)
		(fp_line
			(start -1.2954 -0.5842)
			(end 1.2954 -0.5842)
			(stroke
				(width 0.1524)
				(type default)
			)
			(layer "F.SilkS")
		)
		(fp_line
			(start 1.2954 -0.5842)
			(end 1.2954 0.5842)
			(stroke
				(width 0.1524)
				(type default)
			)
			(layer "F.SilkS")
		)
		(fp_line
			(start -0.8636 0.4572)
			(end -0.8636 0.4318)
			(stroke
				(width 0.1)
				(type default)
			)
			(layer "F.Fab")
		)
		(fp_line
			(start 0.8636 0.4572)
			(end -0.8636 0.4572)
			(stroke
				(width 0.1)
				(type default)
			)
			(layer "F.Fab")
		)
		(fp_line
			(start -0.8636 0.4318)
			(end -0.8636 0.4064)
			(stroke
				(width 0.1)
				(type default)
			)
			(layer "F.Fab")
		)
		(fp_line
			(start -1.1938 0.4064)
			(end -1.1938 -0.406654)
			(stroke
				(width 0.1)
				(type default)
			)
			(layer "F.Fab")
		)
		(fp_line
			(start -0.8636 0.4064)
			(end -1.1938 0.4064)
			(stroke
				(width 0.1)
				(type default)
			)
			(layer "F.Fab")
		)
		(fp_line
			(start 0.8636 0.4064)
			(end 0.8636 0.4572)
			(stroke
				(width 0.1)
				(type default)
			)
			(layer "F.Fab")
		)
		(fp_line
			(start 1.1938 0.4064)
			(end 0.8636 0.4064)
			(stroke
				(width 0.1)
				(type default)
			)
			(layer "F.Fab")
		)
		(fp_line
			(start -1.1938 -0.406654)
			(end -0.8636 -0.406654)
			(stroke
				(width 0.1)
				(type default)
			)
			(layer "F.Fab")
		)
		(fp_line
			(start -0.8636 -0.406654)
			(end -0.8636 -0.4572)
			(stroke
				(width 0.1)
				(type default)
			)
			(layer "F.Fab")
		)
		(fp_line
			(start 0.8636 -0.406654)
			(end 1.1938 -0.406654)
			(stroke
				(width 0.1)
				(type default)
			)
			(layer "F.Fab")
		)
		(fp_line
			(start 1.1938 -0.406654)
			(end 1.1938 0.4064)
			(stroke
				(width 0.1)
				(type default)
			)
			(layer "F.Fab")
		)
		(fp_line
			(start -0.8636 -0.4572)
			(end 0.8636 -0.4572)
			(stroke
				(width 0.1)
				(type default)
			)
			(layer "F.Fab")
		)
		(fp_line
			(start 0.8636 -0.4572)
			(end 0.8636 -0.406654)
			(stroke
				(width 0.1)
				(type default)
			)
			(layer "F.Fab")
		)
		(pad "1" smd rect
			(at -0.7366 0 180)
			(size 0.7112 0.8128)
			(layers "F.Cu" "F.Mask" "F.Paste")
			(net "P12V_BRICK")
		)
		(pad "2" smd rect
			(at 0.7366 0 180)
			(size 0.7112 0.8128)
			(layers "F.Cu" "F.Mask" "F.Paste")
			(net "P12V_HPDB_0_PD")
		)
	)
	(footprint ""
		(layer "F.Cu")
		(at 168.148 -51.816)
		(property "Reference" "PC32"
			(at 0 0 0)
			(layer "F.SilkS")
			(hide yes)
			(effects
				(font
					(size 1.27 1.27)
				)
			)
		)
		(property "Value" ""
			(at 0 0 0)
			(layer "F.Fab")
			(effects
				(font
					(size 1.27 1.27)
				)
			)
		)
		(duplicate_pad_numbers_are_jumpers no)
		(fp_line
			(start -1.524 -0.762)
			(end 1.524 -0.762)
			(stroke
				(width 0.1524)
				(type default)
			)
			(layer "F.SilkS")
		)
		(fp_line
			(start -1.524 0.762)
			(end -1.524 -0.762)
			(stroke
				(width 0.1524)
				(type default)
			)
			(layer "F.SilkS")
		)
		(fp_line
			(start 1.524 -0.762)
			(end 1.524 0.762)
			(stroke
				(width 0.1524)
				(type default)
			)
			(layer "F.SilkS")
		)
		(fp_line
			(start 1.524 0.762)
			(end -1.524 0.762)
			(stroke
				(width 0.1524)
				(type default)
			)
			(layer "F.SilkS")
		)
		(fp_line
			(start -1.1049 -0.724916)
			(end -1.1049 0.724916)
			(stroke
				(width 0.1)
				(type default)
			)
			(layer "F.Fab")
		)
		(fp_line
			(start -1.1049 0.724916)
			(end 1.1049 0.724916)
			(stroke
				(width 0.1)
				(type default)
			)
			(layer "F.Fab")
		)
		(fp_line
			(start 1.1049 -0.724916)
			(end -1.1049 -0.724916)
			(stroke
				(width 0.1)
				(type default)
			)
			(layer "F.Fab")
		)
		(fp_line
			(start 1.1049 0.724916)
			(end 1.1049 -0.724916)
			(stroke
				(width 0.1)
				(type default)
			)
			(layer "F.Fab")
		)
		(pad "1" smd rect
			(at -0.889 0 180)
			(size 1.016 1.27)
			(layers "F.Cu" "F.Mask" "F.Paste")
			(net "P12V_BRICK")
		)
		(pad "2" smd rect
			(at 0.889 0 180)
			(size 1.016 1.27)
			(layers "F.Cu" "F.Mask" "F.Paste")
			(net "GND")
		)
	)
	(footprint ""
		(layer "F.Cu")
		(at 268.732 -47.625 -90)
		(property "Reference" "R5855"
			(at 0 0 270)
			(layer "F.SilkS")
			(hide yes)
			(effects
				(font
					(size 1.27 1.27)
				)
			)
		)
		(property "Value" ""
			(at 0 0 270)
			(layer "F.Fab")
			(effects
				(font
					(size 1.27 1.27)
				)
			)
		)
		(duplicate_pad_numbers_are_jumpers no)
		(fp_line
			(start -0.7874 0.4064)
			(end -0.7874 -0.4064)
			(stroke
				(width 0.1524)
				(type default)
			)
			(layer "F.SilkS")
		)
		(fp_line
			(start 0.7874 0.4064)
			(end -0.7874 0.4064)
			(stroke
				(width 0.1524)
				(type default)
			)
			(layer "F.SilkS")
		)
		(fp_line
			(start -0.7874 -0.4064)
			(end 0.7874 -0.4064)
			(stroke
				(width 0.1524)
				(type default)
			)
			(layer "F.SilkS")
		)
		(fp_line
			(start 0.7874 -0.4064)
			(end 0.7874 0.4064)
			(stroke
				(width 0.1524)
				(type default)
			)
			(layer "F.SilkS")
		)
		(fp_line
			(start -0.67945 0.3048)
			(end -0.67945 -0.305054)
			(stroke
				(width 0.1)
				(type default)
			)
			(layer "F.Fab")
		)
		(fp_line
			(start -0.12065 0.3048)
			(end -0.67945 0.3048)
			(stroke
				(width 0.1)
				(type default)
			)
			(layer "F.Fab")
		)
		(fp_line
			(start 0.120396 0.3048)
			(end 0.120396 0.2794)
			(stroke
				(width 0.1)
				(type default)
			)
			(layer "F.Fab")
		)
		(fp_line
			(start 0.67945 0.3048)
			(end 0.120396 0.3048)
			(stroke
				(width 0.1)
				(type default)
			)
			(layer "F.Fab")
		)
		(fp_line
			(start -0.12065 0.2794)
			(end -0.12065 0.3048)
			(stroke
				(width 0.1)
				(type default)
			)
			(layer "F.Fab")
		)
		(fp_line
			(start 0.120396 0.2794)
			(end -0.12065 0.2794)
			(stroke
				(width 0.1)
				(type default)
			)
			(layer "F.Fab")
		)
		(fp_line
			(start -0.12065 -0.2794)
			(end 0.12065 -0.2794)
			(stroke
				(width 0.1)
				(type default)
			)
			(layer "F.Fab")
		)
		(fp_line
			(start 0.12065 -0.2794)
			(end 0.12065 -0.3048)
			(stroke
				(width 0.1)
				(type default)
			)
			(layer "F.Fab")
		)
		(fp_line
			(start 0.12065 -0.3048)
			(end 0.67945 -0.3048)
			(stroke
				(width 0.1)
				(type default)
			)
			(layer "F.Fab")
		)
		(fp_line
			(start 0.67945 -0.3048)
			(end 0.67945 0.3048)
			(stroke
				(width 0.1)
				(type default)
			)
			(layer "F.Fab")
		)
		(fp_line
			(start -0.67945 -0.305054)
			(end -0.12065 -0.305054)
			(stroke
				(width 0.1)
				(type default)
			)
			(layer "F.Fab")
		)
		(fp_line
			(start -0.12065 -0.305054)
			(end -0.12065 -0.2794)
			(stroke
				(width 0.1)
				(type default)
			)
			(layer "F.Fab")
		)
		(pad "1" smd circle
			(at -0.40005 0 270)
			(size 0 0)
			(layers "F.Cu" "F.Mask" "F.Paste")
			(net "SMB_P52V_HSC_SDA")
		)
		(pad "2" smd circle
			(at 0.40005 0 270)
			(size 0 0)
			(layers "F.Cu" "F.Mask" "F.Paste")
			(net "SMB_P52V_HS1_SDAI")
		)
	)
	(footprint ""
		(layer "F.Cu")
		(at 279.4 -20.955)
		(property "Reference" "R5884"
			(at 0 0 0)
			(layer "F.SilkS")
			(hide yes)
			(effects
				(font
					(size 1.27 1.27)
				)
			)
		)
		(property "Value" ""
			(at 0 0 0)
			(layer "F.Fab")
			(effects
				(font
					(size 1.27 1.27)
				)
			)
		)
		(duplicate_pad_numbers_are_jumpers no)
		(fp_line
			(start -1.651 -0.8382)
			(end 1.651 -0.8382)
			(stroke
				(width 0.1524)
				(type default)
			)
			(layer "F.SilkS")
		)
		(fp_line
			(start -1.651 0.8382)
			(end -1.651 -0.8382)
			(stroke
				(width 0.1524)
				(type default)
			)
			(layer "F.SilkS")
		)
		(fp_line
			(start 1.651 -0.8382)
			(end 1.651 0.8382)
			(stroke
				(width 0.1524)
				(type default)
			)
			(layer "F.SilkS")
		)
		(fp_line
			(start 1.651 0.8382)
			(end -1.651 0.8382)
			(stroke
				(width 0.1524)
				(type default)
			)
			(layer "F.SilkS")
		)
		(fp_line
			(start -1.559814 -0.7366)
			(end -1.559814 0.7366)
			(stroke
				(width 0.1)
				(type default)
			)
			(layer "F.Fab")
		)
		(fp_line
			(start -1.559814 0.7366)
			(end -1.524 0.7366)
			(stroke
				(width 0.1)
				(type default)
			)
			(layer "F.Fab")
		)
		(fp_line
			(start -1.524 -0.7366)
			(end -1.559814 -0.7366)
			(stroke
				(width 0.1)
				(type default)
			)
			(layer "F.Fab")
		)
		(fp_line
			(start -1.524 0.7366)
			(end 1.524 0.7366)
			(stroke
				(width 0.1)
				(type default)
			)
			(layer "F.Fab")
		)
		(fp_line
			(start 1.524 -0.7366)
			(end -1.524 -0.7366)
			(stroke
				(width 0.1)
				(type default)
			)
			(layer "F.Fab")
		)
		(fp_line
			(start 1.524 0.7366)
			(end 1.560576 0.7366)
			(stroke
				(width 0.1)
				(type default)
			)
			(layer "F.Fab")
		)
		(fp_line
			(start 1.560576 -0.7366)
			(end 1.524 -0.7366)
			(stroke
				(width 0.1)
				(type default)
			)
			(layer "F.Fab")
		)
		(fp_line
			(start 1.560576 0.7366)
			(end 1.560576 -0.7366)
			(stroke
				(width 0.1)
				(type default)
			)
			(layer "F.Fab")
		)
		(pad "1" smd rect
			(at -0.94996 0 180)
			(size 1.1176 1.3716)
			(layers "F.Cu" "F.Mask" "F.Paste")
			(net "P52V_BUSBAR")
		)
		(pad "2" smd rect
			(at 0.94996 0 180)
			(size 1.1176 1.3716)
			(layers "F.Cu" "F.Mask" "F.Paste")
			(net "FM_HSC_EN_BUSBAR")
		)
	)
	(footprint ""
		(layer "F.Cu")
		(at 269.875 -47.625 -90)
		(property "Reference" "R5864"
			(at 0 0 270)
			(layer "F.SilkS")
			(hide yes)
			(effects
				(font
					(size 1.27 1.27)
				)
			)
		)
		(property "Value" ""
			(at 0 0 270)
			(layer "F.Fab")
			(effects
				(font
					(size 1.27 1.27)
				)
			)
		)
		(duplicate_pad_numbers_are_jumpers no)
		(fp_line
			(start -0.7874 0.4064)
			(end -0.7874 -0.4064)
			(stroke
				(width 0.1524)
				(type default)
			)
			(layer "F.SilkS")
		)
		(fp_line
			(start 0.7874 0.4064)
			(end -0.7874 0.4064)
			(stroke
				(width 0.1524)
				(type default)
			)
			(layer "F.SilkS")
		)
		(fp_line
			(start -0.7874 -0.4064)
			(end 0.7874 -0.4064)
			(stroke
				(width 0.1524)
				(type default)
			)
			(layer "F.SilkS")
		)
		(fp_line
			(start 0.7874 -0.4064)
			(end 0.7874 0.4064)
			(stroke
				(width 0.1524)
				(type default)
			)
			(layer "F.SilkS")
		)
		(fp_line
			(start -0.67945 0.3048)
			(end -0.67945 -0.305054)
			(stroke
				(width 0.1)
				(type default)
			)
			(layer "F.Fab")
		)
		(fp_line
			(start -0.12065 0.3048)
			(end -0.67945 0.3048)
			(stroke
				(width 0.1)
				(type default)
			)
			(layer "F.Fab")
		)
		(fp_line
			(start 0.120396 0.3048)
			(end 0.120396 0.2794)
			(stroke
				(width 0.1)
				(type default)
			)
			(layer "F.Fab")
		)
		(fp_line
			(start 0.67945 0.3048)
			(end 0.120396 0.3048)
			(stroke
				(width 0.1)
				(type default)
			)
			(layer "F.Fab")
		)
		(fp_line
			(start -0.12065 0.2794)
			(end -0.12065 0.3048)
			(stroke
				(width 0.1)
				(type default)
			)
			(layer "F.Fab")
		)
		(fp_line
			(start 0.120396 0.2794)
			(end -0.12065 0.2794)
			(stroke
				(width 0.1)
				(type default)
			)
			(layer "F.Fab")
		)
		(fp_line
			(start -0.12065 -0.2794)
			(end 0.12065 -0.2794)
			(stroke
				(width 0.1)
				(type default)
			)
			(layer "F.Fab")
		)
		(fp_line
			(start 0.12065 -0.2794)
			(end 0.12065 -0.3048)
			(stroke
				(width 0.1)
				(type default)
			)
			(layer "F.Fab")
		)
		(fp_line
			(start 0.12065 -0.3048)
			(end 0.67945 -0.3048)
			(stroke
				(width 0.1)
				(type default)
			)
			(layer "F.Fab")
		)
		(fp_line
			(start 0.67945 -0.3048)
			(end 0.67945 0.3048)
			(stroke
				(width 0.1)
				(type default)
			)
			(layer "F.Fab")
		)
		(fp_line
			(start -0.67945 -0.305054)
			(end -0.12065 -0.305054)
			(stroke
				(width 0.1)
				(type default)
			)
			(layer "F.Fab")
		)
		(fp_line
			(start -0.12065 -0.305054)
			(end -0.12065 -0.2794)
			(stroke
				(width 0.1)
				(type default)
			)
			(layer "F.Fab")
		)
		(pad "1" smd circle
			(at -0.40005 0 270)
			(size 0 0)
			(layers "F.Cu" "F.Mask" "F.Paste")
			(net "SMB_P52V_HSC_SCL")
		)
		(pad "2" smd circle
			(at 0.40005 0 270)
			(size 0 0)
			(layers "F.Cu" "F.Mask" "F.Paste")
			(net "SMB_P52V_VPDB_SCL_R3")
		)
	)
	(footprint ""
		(layer "F.Cu")
		(at 186.939174 -60.96)
		(property "Reference" "PC136"
			(at -1.773174 -3.52933 0)
			(unlocked yes)
			(layer "F.SilkS")
			(effects
				(font
					(size 0.7874 0.5842)
					(thickness 0.1524)
				)
				(justify left)
			)
		)
		(property "Value" ""
			(at 0 0 0)
			(layer "F.Fab")
			(effects
				(font
					(size 1.27 1.27)
				)
			)
		)
		(duplicate_pad_numbers_are_jumpers no)
		(fp_line
			(start 5.2578 2.499868)
			(end -5.2578 2.499868)
			(stroke
				(width 0.1524)
				(type default)
			)
			(layer "F.SilkS")
		)
		(fp_circle
			(center 0 2.499868)
			(end 5.2578 2.499868)
			(stroke
				(width 0.1524)
				(type default)
			)
			(fill no)
			(layer "F.SilkS")
		)
		(fp_poly
			(pts
				(arc
					(start 5.2578 2.499868)
					(mid 0 7.757922)
					(end -5.2578 2.499868)
				)
			)
			(stroke
				(width 0)
				(type default)
			)
			(fill yes)
			(layer "F.SilkS")
		)
		(fp_circle
			(center 0 2.499868)
			(end 5.2578 2.499868)
			(stroke
				(width 0.1)
				(type default)
			)
			(fill no)
			(layer "F.Fab")
		)
		(pad "1" thru_hole rect
			(at 0 0 270)
			(size 1.524 1.524)
			(drill 1.016)
			(layers "*.Cu" "*.Mask")
			(remove_unused_layers no)
			(net "P12V_BRICK")
			(clearance 0)
			(padstack
				(mode front_inner_back)
				(layer "Inner"
					(shape circle)
					(size 1.524 1.524)
					(clearance 0)
				)
				(layer "B.Cu"
					(shape rect)
					(size 1.524 1.524)
					(clearance 0)
				)
			)
		)
		(pad "2" thru_hole circle
			(at 0 4.99999 270)
			(size 1.524 1.524)
			(drill 1.016)
			(layers "*.Cu" "*.Mask")
			(remove_unused_layers no)
			(net "GND")
			(clearance 0)
		)
	)
)
